(kicad_pcb
	(version 20241229)
	(generator "pcbnew")
	(generator_version "9.0")
	(general
		(thickness 1.61)
		(legacy_teardrops no)
	)
	(paper "A3")
	(title_block
		(title "SO-DIMM DDR5 Tester")
		(date "2025-11-26")
		(rev "1.3.0")
		(comment 9 "footprints 128-132 of 627")
	)
	(layers
		(0 "F.Cu" signal)
		(4 "In1.Cu" power)
		(6 "In2.Cu" mixed)
		(8 "In3.Cu" power)
		(10 "In4.Cu" mixed)
		(12 "In5.Cu" power)
		(14 "In6.Cu" mixed)
		(16 "In7.Cu" power)
		(18 "In8.Cu" power)
		(20 "In9.Cu" mixed)
		(22 "In10.Cu" power)
		(2 "B.Cu" signal)
		(9 "F.Adhes" user "F.Adhesive")
		(11 "B.Adhes" user "B.Adhesive")
		(13 "F.Paste" user)
		(15 "B.Paste" user)
		(5 "F.SilkS" user "F.Silkscreen")
		(7 "B.SilkS" user "B.Silkscreen")
		(1 "F.Mask" user)
		(3 "B.Mask" user)
		(17 "Dwgs.User" user "User.Drawings")
		(19 "Cmts.User" user "User.Comments")
		(21 "Eco1.User" user "User.Eco1")
		(23 "Eco2.User" user "User.Eco2")
		(25 "Edge.Cuts" user)
		(27 "Margin" user)
		(31 "F.CrtYd" user "F.Courtyard")
		(29 "B.CrtYd" user "B.Courtyard")
		(35 "F.Fab" user)
		(33 "B.Fab" user)
	)
	(footprint "antmicro-footprints:SC70-3"
		(layer "F.Cu")
		(at 192.65 144.45)
		(property "Reference" "Q17"
			(at 0 -1.6 0)
			(layer "F.SilkS")
			(hide yes)
			(effects
				(font
					(size 0.7 0.7)
					(thickness 0.15)
				)
				(justify left bottom)
			)
		)
		(property "Value" "BSS138PW,115"
			(at 0 2.3 0)
			(layer "F.Fab")
			(effects
				(font
					(size 0.7 0.7)
					(thickness 0.15)
				)
				(justify left bottom)
			)
		)
		(property "Datasheet" "https://assets.nexperia.com/documents/data-sheet/BSS138PW.pdf"
			(at 0 0 0)
			(layer "F.Fab")
			(hide yes)
			(effects
				(font
					(size 1.27 1.27)
					(thickness 0.15)
				)
			)
		)
		(property "Description" "Power MOSFET, N Channel, 60 V, 320 mA, 0.9 ohm, SOT-323, Surface Mount"
			(at 0 0 0)
			(layer "F.Fab")
			(hide yes)
			(effects
				(font
					(size 1.27 1.27)
					(thickness 0.15)
				)
			)
		)
		(property "Author" "Antmicro"
			(at 0 0 0)
			(layer "F.Fab")
			(hide yes)
			(effects
				(font
					(size 1 1)
					(thickness 0.15)
				)
			)
		)
		(property "License" "Apache-2.0"
			(at 0 0 0)
			(layer "F.Fab")
			(hide yes)
			(effects
				(font
					(size 1 1)
					(thickness 0.15)
				)
			)
		)
		(property "MPN" "BSS138PW,115"
			(at 0 0 0)
			(layer "F.Fab")
			(hide yes)
			(effects
				(font
					(size 1 1)
					(thickness 0.15)
				)
			)
		)
		(property "Manufacturer" "Nexperia"
			(at 0 0 0)
			(layer "F.Fab")
			(hide yes)
			(effects
				(font
					(size 1 1)
					(thickness 0.15)
				)
			)
		)
		(sheetname "/Supply/")
		(sheetfile "supply.kicad_sch")
		(attr smd)
		(fp_line
			(start -0.3 -1)
			(end 0.627 -0.999)
			(stroke
				(width 0.15)
				(type solid)
			)
			(layer "F.SilkS")
		)
		(fp_line
			(start -0.3 1)
			(end 0.627 1.001)
			(stroke
				(width 0.15)
				(type solid)
			)
			(layer "F.SilkS")
		)
		(fp_line
			(start 0.627 -0.6)
			(end 0.627 -0.999)
			(stroke
				(width 0.15)
				(type solid)
			)
			(layer "F.SilkS")
		)
		(fp_line
			(start 0.627 0.6)
			(end 0.627 1.001)
			(stroke
				(width 0.15)
				(type solid)
			)
			(layer "F.SilkS")
		)
		(fp_line
			(start -1.4 1)
			(end -1.4 -1)
			(stroke
				(width 0.05)
				(type solid)
			)
			(layer "F.CrtYd")
		)
		(fp_line
			(start -0.9 -1.3)
			(end -0.9 -1)
			(stroke
				(width 0.05)
				(type solid)
			)
			(layer "F.CrtYd")
		)
		(fp_line
			(start -0.9 -1.3)
			(end 0.9 -1.3)
			(stroke
				(width 0.05)
				(type solid)
			)
			(layer "F.CrtYd")
		)
		(fp_line
			(start -0.9 -1)
			(end -1.4 -1)
			(stroke
				(width 0.05)
				(type solid)
			)
			(layer "F.CrtYd")
		)
		(fp_line
			(start -0.9 1)
			(end -1.4 1)
			(stroke
				(width 0.05)
				(type solid)
			)
			(layer "F.CrtYd")
		)
		(fp_line
			(start -0.9 1.3)
			(end -0.9 1)
			(stroke
				(width 0.05)
				(type solid)
			)
			(layer "F.CrtYd")
		)
		(fp_line
			(start 0.9 -1.3)
			(end 0.9 -0.4)
			(stroke
				(width 0.05)
				(type solid)
			)
			(layer "F.CrtYd")
		)
		(fp_line
			(start 0.9 -0.4)
			(end 1.4 -0.4)
			(stroke
				(width 0.05)
				(type solid)
			)
			(layer "F.CrtYd")
		)
		(fp_line
			(start 0.9 0.4)
			(end 0.9 1.3)
			(stroke
				(width 0.05)
				(type solid)
			)
			(layer "F.CrtYd")
		)
		(fp_line
			(start 0.9 1.3)
			(end -0.9 1.3)
			(stroke
				(width 0.05)
				(type solid)
			)
			(layer "F.CrtYd")
		)
		(fp_line
			(start 1.4 -0.4)
			(end 1.4 0.4)
			(stroke
				(width 0.05)
				(type solid)
			)
			(layer "F.CrtYd")
		)
		(fp_line
			(start 1.4 0.4)
			(end 0.9 0.4)
			(stroke
				(width 0.05)
				(type solid)
			)
			(layer "F.CrtYd")
		)
		(fp_rect
			(start -0.623 -0.999)
			(end 0.627 1.001)
			(stroke
				(width 0.15)
				(type solid)
			)
			(fill no)
			(layer "F.Fab")
		)
		(pad "1" smd rect
			(at -1.051 -0.65 90)
			(size 0.6 0.6)
			(layers "F.Cu" "F.Mask" "F.Paste")
			(net 368 "Net-(Q17-G)")
			(pinfunction "G")
			(pintype "input")
		)
		(pad "2" smd rect
			(at -1.051 0.65 90)
			(size 0.6 0.6)
			(layers "F.Cu" "F.Mask" "F.Paste")
			(net 1 "GND")
			(pinfunction "S")
			(pintype "passive")
		)
		(pad "3" smd rect
			(at 1.05 0 90)
			(size 0.6 0.6)
			(layers "F.Cu" "F.Mask" "F.Paste")
			(net 62 "/Supply/SEQ_EN")
			(pinfunction "D")
			(pintype "passive")
		)
	)
	(footprint "antmicro-footprints:BarrelJack_Pin2mm_PJ-002AH"
		(layer "F.Cu")
		(at 192.883 128.135)
		(property "Reference" "J7"
			(at -0.4 -6.6 0)
			(layer "F.SilkS")
			(effects
				(font
					(size 0.7 0.7)
					(thickness 0.15)
				)
				(justify left bottom)
			)
		)
		(property "Value" "BarrelJack_Pin2mm_MJ-179PH"
			(at -1.85 6.5 0)
			(layer "F.Fab")
			(effects
				(font
					(size 0.7 0.7)
					(thickness 0.15)
				)
				(justify left bottom)
			)
		)
		(property "Datasheet" "https://www.cuidevices.com/product/resource/pj-002ah.pdf"
			(at 0 0 0)
			(layer "F.Fab")
			(hide yes)
			(effects
				(font
					(size 1.27 1.27)
					(thickness 0.15)
				)
			)
		)
		(property "Description" "Barrel power connector"
			(at 0 0 0)
			(layer "F.Fab")
			(hide yes)
			(effects
				(font
					(size 1.27 1.27)
					(thickness 0.15)
				)
			)
		)
		(property "MPN" "PJ-002AH"
			(at 0 0 0)
			(unlocked yes)
			(layer "F.Fab")
			(hide yes)
			(effects
				(font
					(size 1 1)
					(thickness 0.15)
				)
			)
		)
		(property "Manufacturer" "CUI Inc"
			(at 0 0 0)
			(unlocked yes)
			(layer "F.Fab")
			(hide yes)
			(effects
				(font
					(size 1 1)
					(thickness 0.15)
				)
			)
		)
		(property "Author" "Antmicro"
			(at 0 0 0)
			(unlocked yes)
			(layer "F.Fab")
			(hide yes)
			(effects
				(font
					(size 1 1)
					(thickness 0.15)
				)
			)
		)
		(property "License" "Apache-2.0"
			(at 0 0 0)
			(unlocked yes)
			(layer "F.Fab")
			(hide yes)
			(effects
				(font
					(size 1 1)
					(thickness 0.15)
				)
			)
		)
		(sheetname "/Supply/")
		(sheetfile "supply.kicad_sch")
		(attr through_hole)
		(fp_line
			(start -0.7 -4.55)
			(end 0.45 -4.55)
			(stroke
				(width 0.15)
				(type solid)
			)
			(layer "F.SilkS")
		)
		(fp_line
			(start -0.7 -2.6)
			(end -0.7 -4.55)
			(stroke
				(width 0.15)
				(type solid)
			)
			(layer "F.SilkS")
		)
		(fp_line
			(start -0.7 4.5)
			(end -0.7 2.65)
			(stroke
				(width 0.15)
				(type solid)
			)
			(layer "F.SilkS")
		)
		(fp_line
			(start 5.55 -4.5)
			(end 13.7 -4.5)
			(stroke
				(width 0.15)
				(type solid)
			)
			(layer "F.SilkS")
		)
		(fp_line
			(start 13.7 -4.5)
			(end 13.7 4.5)
			(stroke
				(width 0.15)
				(type solid)
			)
			(layer "F.SilkS")
		)
		(fp_line
			(start 13.7 4.5)
			(end -0.7 4.5)
			(stroke
				(width 0.15)
				(type solid)
			)
			(layer "F.SilkS")
		)
		(fp_circle
			(center -1.3 2.8)
			(end -1.2 2.9)
			(stroke
				(width 0.15)
				(type solid)
			)
			(fill yes)
			(layer "F.SilkS")
		)
		(fp_rect
			(start 14.1 5)
			(end -1.7 -6.2)
			(stroke
				(width 0.05)
				(type default)
			)
			(fill no)
			(layer "F.CrtYd")
		)
		(fp_line
			(start -0.7 -4.5)
			(end 13.7 -4.5)
			(stroke
				(width 0.15)
				(type solid)
			)
			(layer "F.Fab")
		)
		(fp_line
			(start -0.7 4.5)
			(end -0.7 -4.5)
			(stroke
				(width 0.15)
				(type solid)
			)
			(layer "F.Fab")
		)
		(fp_line
			(start 13.7 -4.5)
			(end 13.7 4.5)
			(stroke
				(width 0.15)
				(type solid)
			)
			(layer "F.Fab")
		)
		(fp_line
			(start 13.7 4.5)
			(end -0.7 4.5)
			(stroke
				(width 0.15)
				(type solid)
			)
			(layer "F.Fab")
		)
		(fp_circle
			(center -1.3 2.8)
			(end -1.159 2.8)
			(stroke
				(width 0.15)
				(type solid)
			)
			(fill yes)
			(layer "F.Fab")
		)
		(fp_text user "Author: Antmicro"
			(at -1.85 9.7 0)
			(layer "F.Fab")
			(effects
				(font
					(size 0.7 0.7)
					(thickness 0.15)
				)
				(justify left bottom)
			)
		)
		(fp_text user "License: Apache-2.0"
			(at -1.85 10.9 0)
			(layer "F.Fab")
			(effects
				(font
					(size 0.7 0.7)
					(thickness 0.15)
				)
				(justify left bottom)
			)
		)
		(fp_text user "${REFERENCE}"
			(at -1.85 8.5 0)
			(layer "F.Fab")
			(effects
				(font
					(size 0.7 0.7)
					(thickness 0.15)
				)
				(justify left bottom)
			)
		)
		(pad "1" thru_hole oval
			(at 0 0)
			(size 2.5 5)
			(drill oval 1 3.5)
			(layers "*.Cu" "*.Mask")
			(remove_unused_layers no)
			(net 597 "/Supply/12V_aux")
			(pintype "passive")
			(solder_mask_margin 0.102)
		)
		(pad "2" thru_hole oval
			(at 6 0)
			(size 2.25 4.5)
			(drill oval 1 3)
			(layers "*.Cu" "*.Mask")
			(remove_unused_layers no)
			(net 1 "GND")
			(pintype "passive")
			(solder_mask_margin 0.102)
		)
		(pad "3" thru_hole oval
			(at 3 -4.7)
			(size 4.5 2.25)
			(drill oval 3 1)
			(layers "*.Cu" "*.Mask")
			(remove_unused_layers no)
			(net 1 "GND")
			(pintype "passive")
			(solder_mask_margin 0.102)
		)
	)
	(footprint "antmicro-footprints:VSSOP-8_2.3x2mm_P0.5mm"
		(layer "F.Cu")
		(at 181.65 198.05)
		(property "Reference" "U23"
			(at -1.15 2.1 0)
			(layer "F.SilkS")
			(effects
				(font
					(size 0.7 0.7)
					(thickness 0.15)
				)
				(justify left bottom)
			)
		)
		(property "Value" "TS5A3359_VSSOP"
			(at 0 2.258 0)
			(layer "F.Fab")
			(effects
				(font
					(size 0.7 0.7)
					(thickness 0.15)
				)
				(justify left bottom)
			)
		)
		(property "Datasheet" "https://www.ti.com/general/docs/suppproductinfo.tsp?distId=26&gotoUrl=http%3A%2F%2Fwww.ti.com%2Flit%2Fgpn%2Fts5a3359"
			(at 0 0 0)
			(layer "F.Fab")
			(hide yes)
			(effects
				(font
					(size 1.27 1.27)
					(thickness 0.15)
				)
			)
		)
		(property "Author" "Antmicro"
			(at 0 0 0)
			(layer "F.Fab")
			(hide yes)
			(effects
				(font
					(size 1 1)
					(thickness 0.15)
				)
			)
		)
		(property "License" "Apache-2.0"
			(at 0 0 0)
			(layer "F.Fab")
			(hide yes)
			(effects
				(font
					(size 1 1)
					(thickness 0.15)
				)
			)
		)
		(property "MPN" "TS5A3359DCUR"
			(at 0 0 0)
			(layer "F.Fab")
			(hide yes)
			(effects
				(font
					(size 1 1)
					(thickness 0.15)
				)
			)
		)
		(property "Manufacturer" "Texas Instruments"
			(at 0 0 0)
			(layer "F.Fab")
			(hide yes)
			(effects
				(font
					(size 1 1)
					(thickness 0.15)
				)
			)
		)
		(sheetname "/I^{2}C/")
		(sheetfile "i2c.kicad_sch")
		(attr smd)
		(fp_line
			(start -0.82 -0.992)
			(end 0.825 -0.992)
			(stroke
				(width 0.15)
				(type solid)
			)
			(layer "F.SilkS")
		)
		(fp_line
			(start 0.825 1.007)
			(end -0.82 1.007)
			(stroke
				(width 0.15)
				(type solid)
			)
			(layer "F.SilkS")
		)
		(fp_circle
			(center -1.402 -1.192)
			(end -1.352 -1.192)
			(stroke
				(width 0.15)
				(type solid)
			)
			(fill yes)
			(layer "F.SilkS")
		)
		(fp_rect
			(start 1.8 1.35)
			(end -1.8 -1.35)
			(stroke
				(width 0.05)
				(type solid)
			)
			(fill no)
			(layer "F.CrtYd")
		)
		(fp_line
			(start -0.7 -0.99)
			(end -1.14 -0.55)
			(stroke
				(width 0.15)
				(type solid)
			)
			(layer "F.Fab")
		)
		(fp_rect
			(start -1.147 -0.992)
			(end 1.151 1.007)
			(stroke
				(width 0.15)
				(type solid)
			)
			(fill no)
			(layer "F.Fab")
		)
		(pad "1" smd rect
			(at -1.372 -0.742)
			(size 0.75 0.4)
			(layers "F.Cu" "F.Mask" "F.Paste")
			(net 683 "/FPGA bank 14/FPGA_DDR.SDA")
			(pinfunction "NO1")
			(pintype "passive")
		)
		(pad "2" smd rect
			(at -1.372 -0.244)
			(size 0.75 0.3)
			(layers "F.Cu" "F.Mask" "F.Paste")
			(net 688 "/FPGA bank 14/FPGA_PWR.SDA")
			(pinfunction "NO2")
			(pintype "passive")
		)
		(pad "3" smd rect
			(at -1.372 0.256)
			(size 0.75 0.3)
			(layers "F.Cu" "F.Mask" "F.Paste")
			(net 672 "/Debug FTDI/FTDI.SDA")
			(pinfunction "NO3")
			(pintype "passive")
		)
		(pad "4" smd rect
			(at -1.372 0.757)
			(size 0.75 0.4)
			(layers "F.Cu" "F.Mask" "F.Paste")
			(net 1 "GND")
			(pinfunction "GND")
			(pintype "passive")
		)
		(pad "5" smd rect
			(at 1.377 0.757)
			(size 0.75 0.4)
			(layers "F.Cu" "F.Mask" "F.Paste")
			(net 687 "IN2")
			(pinfunction "IN2")
			(pintype "passive")
		)
		(pad "6" smd rect
			(at 1.377 0.256)
			(size 0.75 0.3)
			(layers "F.Cu" "F.Mask" "F.Paste")
			(net 686 "IN1")
			(pinfunction "IN1")
			(pintype "passive")
		)
		(pad "7" smd rect
			(at 1.377 -0.244)
			(size 0.75 0.3)
			(layers "F.Cu" "F.Mask" "F.Paste")
			(net 690 "/I^{2}C/PWR.SDA")
			(pinfunction "COM")
			(pintype "passive")
		)
		(pad "8" smd rect
			(at 1.377 -0.742)
			(size 0.75 0.4)
			(layers "F.Cu" "F.Mask" "F.Paste")
			(net 41 "+3V3_AON")
			(pinfunction "VCC")
			(pintype "passive")
		)
	)
	(footprint "antmicro-footprints:R_0402_1005Metric"
		(layer "F.Cu")
		(at 98.360501 146.556)
		(descr "Resistor SMD 0402")
		(tags "resistor SMD 0402")
		(property "Reference" "R123"
			(at -1.122484 -0.772697 0)
			(layer "F.SilkS")
			(hide yes)
			(effects
				(font
					(size 0.7 0.7)
					(thickness 0.15)
				)
				(justify left bottom)
			)
		)
		(property "Value" "R_4k7_0402"
			(at -1.011843 1.772047 0)
			(layer "F.Fab")
			(effects
				(font
					(size 0.7 0.7)
					(thickness 0.15)
				)
				(justify left bottom)
			)
		)
		(property "Datasheet" "https://www.bourns.com/docs/product-datasheets/cr.pdf"
			(at 0 0 0)
			(layer "F.Fab")
			(hide yes)
			(effects
				(font
					(size 1.27 1.27)
					(thickness 0.15)
				)
			)
		)
		(property "Author" "Antmicro"
			(at 0 0 0)
			(layer "F.Fab")
			(hide yes)
			(effects
				(font
					(size 1 1)
					(thickness 0.15)
				)
			)
		)
		(property "License" "Apache-2.0"
			(at 0 0 0)
			(layer "F.Fab")
			(hide yes)
			(effects
				(font
					(size 1 1)
					(thickness 0.15)
				)
			)
		)
		(property "MPN" "CR0402-FX-4701GLF"
			(at 0 0 0)
			(layer "F.Fab")
			(hide yes)
			(effects
				(font
					(size 1 1)
					(thickness 0.15)
				)
			)
		)
		(property "Manufacturer" "Bourns"
			(at 0 0 0)
			(layer "F.Fab")
			(hide yes)
			(effects
				(font
					(size 1 1)
					(thickness 0.15)
				)
			)
		)
		(property "Tolerance" "1%"
			(at 0 0 0)
			(layer "F.Fab")
			(hide yes)
			(effects
				(font
					(size 1 1)
					(thickness 0.15)
				)
			)
		)
		(property "Val" "4k7"
			(at 0 0 0)
			(layer "F.Fab")
			(hide yes)
			(effects
				(font
					(size 1 1)
					(thickness 0.15)
				)
			)
		)
		(sheetname "/I^{2}C/")
		(sheetfile "i2c.kicad_sch")
		(attr smd)
		(fp_rect
			(start -0.93 -0.47)
			(end 0.93 0.47)
			(stroke
				(width 0.05)
				(type solid)
			)
			(fill no)
			(layer "F.CrtYd")
		)
		(fp_rect
			(start -0.5 -0.25)
			(end 0.5 0.25)
			(stroke
				(width 0.15)
				(type solid)
			)
			(fill no)
			(layer "F.Fab")
		)
		(pad "1" smd roundrect
			(at -0.485 0)
			(size 0.59 0.64)
			(layers "F.Cu" "F.Mask" "F.Paste")
			(roundrect_rratio 0.25)
			(net 200 "+3V3")
			(pintype "passive")
		)
		(pad "2" smd roundrect
			(at 0.485 0)
			(size 0.59 0.64)
			(layers "F.Cu" "F.Mask" "F.Paste")
			(roundrect_rratio 0.25)
			(net 683 "/FPGA bank 14/FPGA_DDR.SDA")
			(pintype "passive")
		)
	)
	(footprint "antmicro-footprints:C_0402_1005Metric"
		(layer "F.Cu")
		(at 177.219502 192.714502 -90)
		(descr "Capacitor SMD 0402")
		(tags "capacitor SMD 0402")
		(property "Reference" "C210"
			(at 0 -0.699 270)
			(layer "F.SilkS")
			(hide yes)
			(effects
				(font
					(size 0.7 0.7)
					(thickness 0.15)
				)
				(justify left bottom)
			)
		)
		(property "Value" "C_22n_0402"
			(at -1.022927 2.155213 270)
			(layer "F.Fab")
			(effects
				(font
					(size 0.7 0.7)
					(thickness 0.15)
				)
				(justify left bottom)
			)
		)
		(property "Datasheet" "https://www.murata.com/products/productdetail?partno=GCM155R71H223MA55%23"
			(at 0 0 270)
			(layer "F.Fab")
			(hide yes)
			(effects
				(font
					(size 1.27 1.27)
					(thickness 0.15)
				)
			)
		)
		(property "Author" "Antmicro"
			(at -15.495 369.934004 0)
			(layer "F.Fab")
			(hide yes)
			(effects
				(font
					(size 1 1)
					(thickness 0.15)
				)
			)
		)
		(property "Dielectric" ""
			(at -15.495 369.934004 0)
			(layer "F.Fab")
			(hide yes)
			(effects
				(font
					(size 1 1)
					(thickness 0.15)
				)
			)
		)
		(property "License" "Apache-2.0"
			(at -15.495 369.934004 0)
			(layer "F.Fab")
			(hide yes)
			(effects
				(font
					(size 1 1)
					(thickness 0.15)
				)
			)
		)
		(property "MPN" "GCM155R71H223MA55D"
			(at -15.495 369.934004 0)
			(layer "F.Fab")
			(hide yes)
			(effects
				(font
					(size 1 1)
					(thickness 0.15)
				)
			)
		)
		(property "Manufacturer" "Murata"
			(at -15.495 369.934004 0)
			(layer "F.Fab")
			(hide yes)
			(effects
				(font
					(size 1 1)
					(thickness 0.15)
				)
			)
		)
		(property "Val" "22n"
			(at -15.495 369.934004 0)
			(layer "F.Fab")
			(hide yes)
			(effects
				(font
					(size 1 1)
					(thickness 0.15)
				)
			)
		)
		(property "Voltage" ""
			(at -15.495 369.934004 0)
			(layer "F.Fab")
			(hide yes)
			(effects
				(font
					(size 1 1)
					(thickness 0.15)
				)
			)
		)
		(sheetname "/Supply/")
		(sheetfile "supply.kicad_sch")
		(attr smd)
		(fp_rect
			(start -0.9659 -0.481258)
			(end 0.9649 0.458742)
			(stroke
				(width 0.05)
				(type solid)
			)
			(fill no)
			(layer "F.CrtYd")
		)
		(fp_line
			(start -0.499 0.248)
			(end -0.499 -0.25)
			(stroke
				(width 0.15)
				(type solid)
			)
			(layer "F.Fab")
		)
		(fp_line
			(start 0.499 0.248)
			(end -0.499 0.248)
			(stroke
				(width 0.15)
				(type solid)
			)
			(layer "F.Fab")
		)
		(fp_line
			(start -0.499 -0.25)
			(end 0.499 -0.25)
			(stroke
				(width 0.15)
				(type solid)
			)
			(layer "F.Fab")
		)
		(fp_line
			(start 0.499 -0.25)
			(end 0.499 0.248)
			(stroke
				(width 0.15)
				(type solid)
			)
			(layer "F.Fab")
		)
		(pad "1" smd roundrect
			(at -0.484 0 270)
			(size 0.59 0.64)
			(layers "F.Cu" "F.Mask" "F.Paste")
			(roundrect_rratio 0.25)
			(net 1 "GND")
			(pintype "passive")
		)
		(pad "2" smd roundrect
			(at 0.484 0 270)
			(size 0.59 0.64)
			(layers "F.Cu" "F.Mask" "F.Paste")
			(roundrect_rratio 0.25)
			(net 75 "/Supply/1V0_SS")
			(pintype "passive")
		)
	)
)
